(kicad_pcb
	(version 20260206)
	(generator "pcbnew")
	(generator_version "10.0")
	(general
		(thickness 1.6)
		(legacy_teardrops no)
	)
	(paper "A4")
	(title_block
		(title "04192023_DAF0TMB3IC0_F0TG_MB_C_brd_V02_OCP.brd")
		(comment 1 "Grand Teton / footprint 3955 of 8354 (U25), pads 4897-5007 of 6102")
	)
	(layers
		(0 "F.Cu" signal "TOP")
		(4 "In1.Cu" signal "GND")
		(6 "In2.Cu" signal "IN1")
		(8 "In3.Cu" signal "GND1")
		(10 "In4.Cu" signal "IN2")
		(12 "In5.Cu" signal "GND2")
		(14 "In6.Cu" signal "IN3")
		(16 "In7.Cu" signal "GND3")
		(18 "In8.Cu" signal "VCC")
		(20 "In9.Cu" signal "VCC1")
		(22 "In10.Cu" signal "GND4")
		(24 "In11.Cu" signal "IN4")
		(26 "In12.Cu" signal "GND5")
		(28 "In13.Cu" signal "IN5")
		(30 "In14.Cu" signal "GND6")
		(32 "In15.Cu" signal "IN6")
		(34 "In16.Cu" signal "GND7")
		(2 "B.Cu" signal "BOTTOM")
		(9 "F.Adhes" user "F.Adhesive")
		(11 "B.Adhes" user "B.Adhesive")
		(13 "F.Paste" user "Package Geometry/Pastemask Top")
		(15 "B.Paste" user "Package Geometry/Pastemask Bottom")
		(5 "F.SilkS" user "Ref Des/Silkscreen Top")
		(7 "B.SilkS" user "Ref Des/Silkscreen Bottom")
		(1 "F.Mask" user "Board Geometry/Soldermask Top")
		(3 "B.Mask" user "Board Geometry/Soldermask Bottom")
		(17 "Dwgs.User" user "User.Drawings")
		(19 "Cmts.User" user "User.Comments")
		(21 "Eco1.User" user "User.Eco1")
		(23 "Eco2.User" user "User.Eco2")
		(25 "Edge.Cuts" user "Board Geometry/Outline")
		(27 "Margin" user)
		(31 "F.CrtYd" user "Package Geometry/Place Bound Top")
		(29 "B.CrtYd" user "Package Geometry/Place Bound Bottom")
		(35 "F.Fab" user "Ref Des/Assembly Top")
		(33 "B.Fab" user "Ref Des/Assembly Bottom")
	)
	(footprint ""
		(layer "F.Cu")
		(at 359.867962 -258.880102 180)
		(property "Reference" "U25"
			(at -45.78477 -62.086744 0)
			(unlocked yes)
			(layer "F.SilkS")
			(effects
				(font
					(size 0.7874 0.5842)
					(thickness 0.1524)
				)
			)
		)
		(property "Value" ""
			(at 0 0 180)
			(layer "F.Fab")
			(effects
				(font
					(size 1.27 1.27)
				)
			)
		)
		(duplicate_pad_numbers_are_jumpers no)
		(pad "DJ5" smd circle
			(at -30.699964 36.809934 180)
			(size 0.450088 0.450088)
			(layers "F.Cu" "F.Mask" "F.Paste")
			(net "CPU0_SLP_S3_N")
		)
		(pad "DJ7" smd circle
			(at -28.82011 36.809934 180)
			(size 0.450088 0.450088)
			(layers "F.Cu" "F.Mask" "F.Paste")
			(net "GND")
		)
		(pad "DJ8" smd circle
			(at -27.880056 36.809934 180)
			(size 0.450088 0.450088)
			(layers "F.Cu" "F.Mask" "F.Paste")
			(net "CPU0_PWR_GOOD")
		)
		(pad "DJ9" smd circle
			(at -26.940002 36.809934 180)
			(size 0.450088 0.450088)
			(layers "F.Cu" "F.Mask" "F.Paste")
			(net "CPU0_THERMTRIP_N")
		)
		(pad "DJ10" smd circle
			(at -25.999948 36.809934 180)
			(size 0.450088 0.450088)
			(layers "F.Cu" "F.Mask" "F.Paste")
			(net "IRQ_WAKE_N")
		)
		(pad "DJ11" smd circle
			(at -25.059894 36.809934 180)
			(size 0.450088 0.450088)
			(layers "F.Cu" "F.Mask" "F.Paste")
			(net "CPU0_SMERR_N")
		)
		(pad "DJ13" smd circle
			(at -23.18004 36.809934 180)
			(size 0.450088 0.450088)
			(layers "F.Cu" "F.Mask" "F.Paste")
			(net "XTAL_CPU0_X32K_X2")
		)
		(pad "DJ14" smd circle
			(at -22.239986 36.809934 180)
			(size 0.450088 0.450088)
			(layers "F.Cu" "F.Mask" "F.Paste")
			(net "XTAL_CPU0_X32K_X1")
		)
		(pad "DJ15" smd circle
			(at -21.299932 36.809934 180)
			(size 0.450088 0.450088)
			(layers "F.Cu" "F.Mask" "F.Paste")
			(net "GND")
		)
		(pad "DJ16" smd circle
			(at -20.359878 36.809934 180)
			(size 0.450088 0.450088)
			(layers "F.Cu" "F.Mask" "F.Paste")
			(net "XTAL_CPU0_X48M_X2")
		)
		(pad "DJ17" smd circle
			(at -19.420078 36.809934 180)
			(size 0.450088 0.450088)
			(layers "F.Cu" "F.Mask" "F.Paste")
			(net "XTAL_CPU0_X48M_X1")
		)
		(pad "DJ19" smd circle
			(at -17.53997 36.809934 180)
			(size 0.450088 0.450088)
			(layers "F.Cu" "F.Mask" "F.Paste")
			(net "GND")
		)
		(pad "DJ20" smd circle
			(at -16.599916 36.809934 180)
			(size 0.450088 0.450088)
			(layers "F.Cu" "F.Mask" "F.Paste")
			(net "SMB_CPU_5_R_SDA")
		)
		(pad "DJ21" smd circle
			(at -15.660116 36.809934 180)
			(size 0.450088 0.450088)
			(layers "F.Cu" "F.Mask" "F.Paste")
			(net "SMB_CPU_5_R_SCL")
		)
		(pad "DJ22" smd circle
			(at -14.720062 36.809934 180)
			(size 0.450088 0.450088)
			(layers "F.Cu" "F.Mask" "F.Paste")
			(net "CPU0_ESPI0_ALERT_N")
		)
		(pad "DJ23" smd circle
			(at -13.780008 36.809934 180)
			(size 0.450088 0.450088)
			(layers "F.Cu" "F.Mask" "F.Paste")
			(net "ESPI_CPU0_R_CS1_N")
		)
		(pad "DJ25" smd circle
			(at -11.8999 36.809934 180)
			(size 0.450088 0.450088)
			(layers "F.Cu" "F.Mask" "F.Paste")
			(net "SPI_CPU0_R_TPM_CS_N")
		)
		(pad "DJ26" smd circle
			(at -10.9601 36.809934 180)
			(size 0.450088 0.450088)
			(layers "F.Cu" "F.Mask" "F.Paste")
			(net "RST_CPU0_KBRST_R_N")
		)
		(pad "DJ27" smd circle
			(at -10.020046 36.809934 180)
			(size 0.450088 0.450088)
			(layers "F.Cu" "F.Mask" "F.Paste")
			(net "SPI_CPU0_R_CLK")
		)
		(pad "DJ28" smd circle
			(at -9.079992 36.809934 180)
			(size 0.450088 0.450088)
			(layers "F.Cu" "F.Mask" "F.Paste")
			(net "SPI_CPU0_R_D2")
		)
		(pad "DJ29" smd circle
			(at -8.139938 36.809934 180)
			(size 0.450088 0.450088)
			(layers "F.Cu" "F.Mask" "F.Paste")
			(net "FM_BIOS_POST_CMPLT_R_N")
		)
		(pad "DJ31" smd circle
			(at -6.260084 36.809934 180)
			(size 0.450088 0.450088)
			(layers "F.Cu" "F.Mask" "F.Paste")
			(net "CPU0_NMI_SYNC_FLOOD_N")
		)
		(pad "DJ32" smd circle
			(at -5.32003 36.809934 180)
			(size 0.450088 0.450088)
			(layers "F.Cu" "F.Mask" "F.Paste")
			(net "UART_CPU0_SCM_UART1_R_TX")
		)
		(pad "DJ33" smd circle
			(at -4.379976 36.809934 180)
			(size 0.450088 0.450088)
			(layers "F.Cu" "F.Mask" "F.Paste")
			(net "FM_BIOS_USB_RECOVERY_R")
		)
		(pad "DJ34" smd circle
			(at -3.439922 36.809934 180)
			(size 0.450088 0.450088)
			(layers "F.Cu" "F.Mask" "F.Paste")
			(net "UART_CPU0_UART0_R_TX")
		)
		(pad "DJ35" smd circle
			(at -2.500122 36.809934 180)
			(size 0.450088 0.450088)
			(layers "F.Cu" "F.Mask" "F.Paste")
			(net "FM_INT_CPU0_HP_UBM_N")
		)
		(pad "DJ41" smd circle
			(at 2.199894 36.809934 180)
			(size 0.450088 0.450088)
			(layers "F.Cu" "F.Mask" "F.Paste")
			(net "CLK_100M_CPU0_CLK11_R_DP")
		)
		(pad "DJ42" smd circle
			(at 3.139948 36.809934 180)
			(size 0.450088 0.450088)
			(layers "F.Cu" "F.Mask" "F.Paste")
			(net "CLK_100M_CPU0_CLK11_R_DN")
		)
		(pad "DJ43" smd circle
			(at 4.080002 36.809934 180)
			(size 0.450088 0.450088)
			(layers "F.Cu" "F.Mask" "F.Paste")
			(net "GND")
		)
		(pad "DJ44" smd circle
			(at 5.020056 36.809934 180)
			(size 0.450088 0.450088)
			(layers "F.Cu" "F.Mask" "F.Paste")
			(net "CLK_100M_CPU0_CLK12_R_DN")
		)
		(pad "DJ45" smd circle
			(at 5.96011 36.809934 180)
			(size 0.450088 0.450088)
			(layers "F.Cu" "F.Mask" "F.Paste")
			(net "CLK_100M_CPU0_CLK12_R_DP")
		)
		(pad "DJ47" smd circle
			(at 7.839964 36.809934 180)
			(size 0.450088 0.450088)
			(layers "F.Cu" "F.Mask" "F.Paste")
			(net "Net_1877")
		)
		(pad "DJ48" smd circle
			(at 8.780018 36.809934 180)
			(size 0.450088 0.450088)
			(layers "F.Cu" "F.Mask" "F.Paste")
			(net "Net_1878")
		)
		(pad "DJ49" smd circle
			(at 9.720072 36.809934 180)
			(size 0.450088 0.450088)
			(layers "F.Cu" "F.Mask" "F.Paste")
			(net "GND")
		)
		(pad "DJ50" smd circle
			(at 10.659872 36.809934 180)
			(size 0.450088 0.450088)
			(layers "F.Cu" "F.Mask" "F.Paste")
			(net "Net_1879")
		)
		(pad "DJ51" smd circle
			(at 11.599926 36.809934 180)
			(size 0.450088 0.450088)
			(layers "F.Cu" "F.Mask" "F.Paste")
			(net "Net_1880")
		)
		(pad "DJ53" smd circle
			(at 13.480034 36.809934 180)
			(size 0.450088 0.450088)
			(layers "F.Cu" "F.Mask" "F.Paste")
			(net "CLK_100M_CPU0_CLK13_R_DP")
		)
		(pad "DJ54" smd circle
			(at 14.420088 36.809934 180)
			(size 0.450088 0.450088)
			(layers "F.Cu" "F.Mask" "F.Paste")
			(net "CLK_100M_CPU0_CLK13_R_DN")
		)
		(pad "DJ55" smd circle
			(at 15.359888 36.809934 180)
			(size 0.450088 0.450088)
			(layers "F.Cu" "F.Mask" "F.Paste")
			(net "CPU0_SA0")
		)
		(pad "DJ56" smd circle
			(at 16.299942 36.809934 180)
			(size 0.450088 0.450088)
			(layers "F.Cu" "F.Mask" "F.Paste")
			(net "CPU0_SA1")
		)
		(pad "DJ57" smd circle
			(at 17.239996 36.809934 180)
			(size 0.450088 0.450088)
			(layers "F.Cu" "F.Mask" "F.Paste")
			(net "Net_1955")
		)
		(pad "DJ59" smd circle
			(at 19.120104 36.809934 180)
			(size 0.450088 0.450088)
			(layers "F.Cu" "F.Mask" "F.Paste")
			(net "GND")
		)
		(pad "DJ60" smd circle
			(at 20.059904 36.809934 180)
			(size 0.450088 0.450088)
			(layers "F.Cu" "F.Mask" "F.Paste")
			(net "USB2_CPU0_P11_DN")
		)
		(pad "DJ61" smd circle
			(at 20.999958 36.809934 180)
			(size 0.450088 0.450088)
			(layers "F.Cu" "F.Mask" "F.Paste")
			(net "GND")
		)
		(pad "DJ62" smd circle
			(at 21.940012 36.809934 180)
			(size 0.450088 0.450088)
			(layers "F.Cu" "F.Mask" "F.Paste")
			(net "Net_1895")
		)
		(pad "DJ63" smd circle
			(at 22.880066 36.809934 180)
			(size 0.450088 0.450088)
			(layers "F.Cu" "F.Mask" "F.Paste")
			(net "GND")
		)
		(pad "DJ65" smd circle
			(at 24.75992 36.809934 180)
			(size 0.450088 0.450088)
			(layers "F.Cu" "F.Mask" "F.Paste")
			(net "Net_1890")
		)
		(pad "DJ66" smd circle
			(at 25.699974 36.809934 180)
			(size 0.450088 0.450088)
			(layers "F.Cu" "F.Mask" "F.Paste")
			(net "GND")
		)
		(pad "DJ67" smd circle
			(at 26.640028 36.809934 180)
			(size 0.450088 0.450088)
			(layers "F.Cu" "F.Mask" "F.Paste")
			(net "USB2_CPU0_P10_DP")
		)
		(pad "DJ68" smd circle
			(at 27.580082 36.809934 180)
			(size 0.450088 0.450088)
			(layers "F.Cu" "F.Mask" "F.Paste")
			(net "GND")
		)
		(pad "DJ69" smd circle
			(at 28.519882 36.809934 180)
			(size 0.450088 0.450088)
			(layers "F.Cu" "F.Mask" "F.Paste")
			(net "Net_1891")
		)
		(pad "DJ71" smd circle
			(at 30.39999 36.809934 180)
			(size 0.450088 0.450088)
			(layers "F.Cu" "F.Mask" "F.Paste")
			(net "SMB_APML_CPU0_SCL")
		)
		(pad "DJ72" smd circle
			(at 31.340044 36.809934 180)
			(size 0.450088 0.450088)
			(layers "F.Cu" "F.Mask" "F.Paste")
			(net "SVID_PVDDCR_CPU1_P0_SVC")
		)
		(pad "DJ73" smd circle
			(at 32.280098 36.809934 180)
			(size 0.450088 0.450088)
			(layers "F.Cu" "F.Mask" "F.Paste")
			(net "GND")
		)
		(pad "E1" smd circle
			(at -34.159952 -33.56991 180)
			(size 0.450088 0.450088)
			(layers "F.Cu" "F.Mask" "F.Paste")
			(net "GND")
		)
		(pad "E2" smd circle
			(at -33.219898 -33.56991 180)
			(size 0.450088 0.450088)
			(layers "F.Cu" "F.Mask" "F.Paste")
			(net "M_G_CPU0_SA_DQ<0>")
		)
		(pad "E3" smd circle
			(at -32.280098 -33.56991 180)
			(size 0.450088 0.450088)
			(layers "F.Cu" "F.Mask" "F.Paste")
			(net "GND")
		)
		(pad "E4" smd circle
			(at -31.340044 -33.56991 180)
			(size 0.450088 0.450088)
			(layers "F.Cu" "F.Mask" "F.Paste")
			(net "PVDDCR_SOC_P0")
		)
		(pad "E5" smd circle
			(at -30.39999 -33.56991 180)
			(size 0.450088 0.450088)
			(layers "F.Cu" "F.Mask" "F.Paste")
			(net "M_K_CPU0_SA_DQ<0>")
		)
		(pad "E6" smd circle
			(at -29.459936 -33.56991 180)
			(size 0.450088 0.450088)
			(layers "F.Cu" "F.Mask" "F.Paste")
			(net "GND")
		)
		(pad "E7" smd circle
			(at -28.519882 -33.56991 180)
			(size 0.450088 0.450088)
			(layers "F.Cu" "F.Mask" "F.Paste")
			(net "GND")
		)
		(pad "E8" smd circle
			(at -27.580082 -33.56991 180)
			(size 0.450088 0.450088)
			(layers "F.Cu" "F.Mask" "F.Paste")
			(net "GND")
		)
		(pad "E9" smd circle
			(at -26.640028 -33.56991 180)
			(size 0.450088 0.450088)
			(layers "F.Cu" "F.Mask" "F.Paste")
			(net "M_L_CPU0_SA_DQ<0>")
		)
		(pad "E10" smd circle
			(at -25.699974 -33.56991 180)
			(size 0.450088 0.450088)
			(layers "F.Cu" "F.Mask" "F.Paste")
			(net "GND")
		)
		(pad "E11" smd circle
			(at -24.75992 -33.56991 180)
			(size 0.450088 0.450088)
			(layers "F.Cu" "F.Mask" "F.Paste")
			(net "PVDDCR_SOC_P0")
		)
		(pad "E12" smd circle
			(at -23.82012 -33.56991 180)
			(size 0.450088 0.450088)
			(layers "F.Cu" "F.Mask" "F.Paste")
			(net "M_H_CPU0_SA_DQ<0>")
		)
		(pad "E13" smd circle
			(at -22.880066 -33.56991 180)
			(size 0.450088 0.450088)
			(layers "F.Cu" "F.Mask" "F.Paste")
			(net "GND")
		)
		(pad "E14" smd circle
			(at -21.940012 -33.56991 180)
			(size 0.450088 0.450088)
			(layers "F.Cu" "F.Mask" "F.Paste")
			(net "GND")
		)
		(pad "E15" smd circle
			(at -20.999958 -33.56991 180)
			(size 0.450088 0.450088)
			(layers "F.Cu" "F.Mask" "F.Paste")
			(net "GND")
		)
		(pad "E16" smd circle
			(at -20.059904 -33.56991 180)
			(size 0.450088 0.450088)
			(layers "F.Cu" "F.Mask" "F.Paste")
			(net "M_J_CPU0_SA_DQ<0>")
		)
		(pad "E17" smd circle
			(at -19.120104 -33.56991 180)
			(size 0.450088 0.450088)
			(layers "F.Cu" "F.Mask" "F.Paste")
			(net "GND")
		)
		(pad "E18" smd circle
			(at -18.18005 -33.56991 180)
			(size 0.450088 0.450088)
			(layers "F.Cu" "F.Mask" "F.Paste")
			(net "GND")
		)
		(pad "E19" smd circle
			(at -17.239996 -33.56991 180)
			(size 0.450088 0.450088)
			(layers "F.Cu" "F.Mask" "F.Paste")
			(net "M_I_CPU0_SA_DQ<0>")
		)
		(pad "E20" smd circle
			(at -16.299942 -33.56991 180)
			(size 0.450088 0.450088)
			(layers "F.Cu" "F.Mask" "F.Paste")
			(net "GND")
		)
		(pad "E21" smd circle
			(at -15.359888 -33.56991 180)
			(size 0.450088 0.450088)
			(layers "F.Cu" "F.Mask" "F.Paste")
			(net "GND")
		)
		(pad "E22" smd circle
			(at -14.420088 -33.56991 180)
			(size 0.450088 0.450088)
			(layers "F.Cu" "F.Mask" "F.Paste")
			(net "PVDDCR_CPU0_P0")
		)
		(pad "E23" smd circle
			(at -13.480034 -33.56991 180)
			(size 0.450088 0.450088)
			(layers "F.Cu" "F.Mask" "F.Paste")
			(net "SCM_USB_OC_BUF_N")
		)
		(pad "E24" smd circle
			(at -12.53998 -33.56991 180)
			(size 0.450088 0.450088)
			(layers "F.Cu" "F.Mask" "F.Paste")
			(net "Net_1883")
		)
		(pad "E25" smd circle
			(at -11.599926 -33.56991 180)
			(size 0.450088 0.450088)
			(layers "F.Cu" "F.Mask" "F.Paste")
			(net "PVDDCR_CPU0_P0")
		)
		(pad "E26" smd circle
			(at -10.659872 -33.56991 180)
			(size 0.450088 0.450088)
			(layers "F.Cu" "F.Mask" "F.Paste")
			(net "USB3_CPU0_BMC_RX_HUB_C_DN")
		)
		(pad "E27" smd circle
			(at -9.720072 -33.56991 180)
			(size 0.450088 0.450088)
			(layers "F.Cu" "F.Mask" "F.Paste")
			(net "USB3_CPU0_BMC_RX_HUB_C_DP")
		)
		(pad "E28" smd circle
			(at -8.780018 -33.56991 180)
			(size 0.450088 0.450088)
			(layers "F.Cu" "F.Mask" "F.Paste")
			(net "PVDDCR_CPU0_P0")
		)
		(pad "E29" smd circle
			(at -7.839964 -33.56991 180)
			(size 0.450088 0.450088)
			(layers "F.Cu" "F.Mask" "F.Paste")
			(net "Net_1886")
		)
		(pad "E30" smd circle
			(at -6.89991 -33.56991 180)
			(size 0.450088 0.450088)
			(layers "F.Cu" "F.Mask" "F.Paste")
			(net "Net_1887")
		)
		(pad "E31" smd circle
			(at -5.96011 -33.56991 180)
			(size 0.450088 0.450088)
			(layers "F.Cu" "F.Mask" "F.Paste")
			(net "PVDDCR_CPU0_P0")
		)
		(pad "E32" smd circle
			(at -5.020056 -33.56991 180)
			(size 0.450088 0.450088)
			(layers "F.Cu" "F.Mask" "F.Paste")
			(net "TP_CPU0_TEST47_CCD3")
		)
		(pad "E33" smd circle
			(at -4.080002 -33.56991 180)
			(size 0.450088 0.450088)
			(layers "F.Cu" "F.Mask" "F.Paste")
			(net "Net_1944")
		)
		(pad "E34" smd circle
			(at -3.139948 -33.56991 180)
			(size 0.450088 0.450088)
			(layers "F.Cu" "F.Mask" "F.Paste")
			(net "PVDDCR_CPU0_P0")
		)
		(pad "E35" smd circle
			(at -2.199894 -33.56991 180)
			(size 0.450088 0.450088)
			(layers "F.Cu" "F.Mask" "F.Paste")
			(net "PVDDCR_CPU0_P0")
		)
		(pad "E36" smd circle
			(at -1.260094 -33.56991 180)
			(size 0.450088 0.450088)
			(layers "F.Cu" "F.Mask" "F.Paste")
			(net "Net_1945")
		)
		(pad "E40" smd circle
			(at 1.560068 -33.56991 180)
			(size 0.450088 0.450088)
			(layers "F.Cu" "F.Mask" "F.Paste")
			(net "Net_1868")
		)
		(pad "E41" smd circle
			(at 2.500122 -33.56991 180)
			(size 0.450088 0.450088)
			(layers "F.Cu" "F.Mask" "F.Paste")
			(net "Net_1867")
		)
		(pad "E42" smd circle
			(at 3.439922 -33.56991 180)
			(size 0.450088 0.450088)
			(layers "F.Cu" "F.Mask" "F.Paste")
			(net "PVDDCR_CPU0_P0")
		)
		(pad "E43" smd circle
			(at 4.379976 -33.56991 180)
			(size 0.450088 0.450088)
			(layers "F.Cu" "F.Mask" "F.Paste")
			(net "P2E_CPU0_P5_RX_DP")
		)
		(pad "E44" smd circle
			(at 5.32003 -33.56991 180)
			(size 0.450088 0.450088)
			(layers "F.Cu" "F.Mask" "F.Paste")
			(net "P2E_CPU0_P5_RX_DN")
		)
		(pad "E45" smd circle
			(at 6.260084 -33.56991 180)
			(size 0.450088 0.450088)
			(layers "F.Cu" "F.Mask" "F.Paste")
			(net "PVDDCR_CPU0_P0")
		)
		(pad "E46" smd circle
			(at 7.199884 -33.56991 180)
			(size 0.450088 0.450088)
			(layers "F.Cu" "F.Mask" "F.Paste")
			(net "Net_1872")
		)
		(pad "E47" smd circle
			(at 8.139938 -33.56991 180)
			(size 0.450088 0.450088)
			(layers "F.Cu" "F.Mask" "F.Paste")
			(net "Net_1871")
		)
		(pad "E48" smd circle
			(at 9.079992 -33.56991 180)
			(size 0.450088 0.450088)
			(layers "F.Cu" "F.Mask" "F.Paste")
			(net "PVDDCR_CPU0_P0")
		)
		(pad "E49" smd circle
			(at 10.020046 -33.56991 180)
			(size 0.450088 0.450088)
			(layers "F.Cu" "F.Mask" "F.Paste")
			(net "WAFL_CPU1_TX1_CPU0_RX0_DP")
		)
		(pad "E50" smd circle
			(at 10.9601 -33.56991 180)
			(size 0.450088 0.450088)
			(layers "F.Cu" "F.Mask" "F.Paste")
			(net "WAFL_CPU1_TX1_CPU0_RX0_DN")
		)
		(pad "E51" smd circle
			(at 11.8999 -33.56991 180)
			(size 0.450088 0.450088)
			(layers "F.Cu" "F.Mask" "F.Paste")
			(net "PVDDCR_CPU0_P0")
		)
		(pad "E52" smd circle
			(at 12.839954 -33.56991 180)
			(size 0.450088 0.450088)
			(layers "F.Cu" "F.Mask" "F.Paste")
			(net "GND")
		)
		(pad "E53" smd circle
			(at 13.780008 -33.56991 180)
			(size 0.450088 0.450088)
			(layers "F.Cu" "F.Mask" "F.Paste")
			(net "GND")
		)
		(pad "E54" smd circle
			(at 14.720062 -33.56991 180)
			(size 0.450088 0.450088)
			(layers "F.Cu" "F.Mask" "F.Paste")
			(net "PVDDCR_CPU0_P0")
		)
		(pad "E55" smd circle
			(at 15.660116 -33.56991 180)
			(size 0.450088 0.450088)
			(layers "F.Cu" "F.Mask" "F.Paste")
			(net "GND")
		)
		(pad "E56" smd circle
			(at 16.599916 -33.56991 180)
			(size 0.450088 0.450088)
			(layers "F.Cu" "F.Mask" "F.Paste")
			(net "GND")
		)
		(pad "E57" smd circle
			(at 17.53997 -33.56991 180)
			(size 0.450088 0.450088)
			(layers "F.Cu" "F.Mask" "F.Paste")
			(net "M_C_CPU0_SA_DQ<0>")
		)
		(pad "E58" smd circle
			(at 18.480024 -33.56991 180)
			(size 0.450088 0.450088)
			(layers "F.Cu" "F.Mask" "F.Paste")
			(net "GND")
		)
		(pad "E59" smd circle
			(at 19.420078 -33.56991 180)
			(size 0.450088 0.450088)
			(layers "F.Cu" "F.Mask" "F.Paste")
			(net "GND")
		)
		(pad "E60" smd circle
			(at 20.359878 -33.56991 180)
			(size 0.450088 0.450088)
			(layers "F.Cu" "F.Mask" "F.Paste")
			(net "M_D_CPU0_SA_DQ<0>")
		)
	)
)
